FILE_TYPE=LIBRARY_PARTS;
primitive 'MOSFET_NCH_DUAL';
  pin
    'S1':
      PIN_NUMBER='(1,0)';
      BIDIRECTIONAL='TRUE';
      INPUT_LOAD='(-0.01,0.01)';
      OUTPUT_LOAD='(1.0,-1.0)';
    'G1':
      PIN_NUMBER='(2,0)';
      BIDIRECTIONAL='TRUE';
      INPUT_LOAD='(-0.01,0.01)';
      OUTPUT_LOAD='(1.0,-1.0)';
    'D1':
      PIN_NUMBER='(6,0)';
      BIDIRECTIONAL='TRUE';
      INPUT_LOAD='(-0.01,0.01)';
      OUTPUT_LOAD='(1.0,-1.0)';
    'D2':
      PIN_NUMBER='(0,3)';
      BIDIRECTIONAL='TRUE';
      INPUT_LOAD='(-0.01,0.01)';
      OUTPUT_LOAD='(1.0,-1.0)';
    'G2':
      PIN_NUMBER='(0,5)';
      BIDIRECTIONAL='TRUE';
      INPUT_LOAD='(-0.01,0.01)';
      OUTPUT_LOAD='(1.0,-1.0)';
    'S2':
      PIN_NUMBER='(0,4)';
      BIDIRECTIONAL='TRUE';
      INPUT_LOAD='(-0.01,0.01)';
      OUTPUT_LOAD='(1.0,-1.0)';
  end_pin;
  body
    PART_NAME='MOSFET_NCH_DUAL';
    BODY_NAME='MOSFET_NCH_DUAL';
    PHYS_DES_PREFIX='Q';
    CLASS='DISCRETE';
  end_body;
end_primitive;

END.
